# T6G (Grand Teton) — schematic netlist excerpt (pin names and nets, part order shuffled) for the footprints in the layout excerpt that follows; sources: Cadence DE-HDL packaged netlist, KiCad conversion of 04192023_DAF0TMB3IC0_F0TG_MB_C_brd_V02_OCP.brd

R908  Q_RES  10K 1% CHIP  pkg 0201LF  page 353 : A = RST_RT_CPU1_P3_RESET_R_N ; B = GND
R1172  Q_RES  10K 5% EMPTY  pkg 0402LF  page 142 : A = P3V3_AUX ; B = OCP_V3_2_AUX_PWR_EN
R6808  Q_RES  1K 1% EMPTY  pkg 0201LF  page 277 : A = P1V8_CPU0_RT_1D ; B = RT_CPU0_P0_VQPS

(kicad_pcb
	(version 20260206)
	(generator "pcbnew")
	(generator_version "10.0")
	(general
		(thickness 1.6)
		(legacy_teardrops no)
	)
	(paper "A4")
	(title_block
		(title "04192023_DAF0TMB3IC0_F0TG_MB_C_brd_V02_OCP.brd")
		(comment 1 "Grand Teton / footprints 2087-2089 of 8354")
	)
	(layers
		(0 "F.Cu" signal "TOP")
		(4 "In1.Cu" signal "GND")
		(6 "In2.Cu" signal "IN1")
		(8 "In3.Cu" signal "GND1")
		(10 "In4.Cu" signal "IN2")
		(12 "In5.Cu" signal "GND2")
		(14 "In6.Cu" signal "IN3")
		(16 "In7.Cu" signal "GND3")
		(18 "In8.Cu" signal "VCC")
		(20 "In9.Cu" signal "VCC1")
		(22 "In10.Cu" signal "GND4")
		(24 "In11.Cu" signal "IN4")
		(26 "In12.Cu" signal "GND5")
		(28 "In13.Cu" signal "IN5")
		(30 "In14.Cu" signal "GND6")
		(32 "In15.Cu" signal "IN6")
		(34 "In16.Cu" signal "GND7")
		(2 "B.Cu" signal "BOTTOM")
		(9 "F.Adhes" user "F.Adhesive")
		(11 "B.Adhes" user "B.Adhesive")
		(13 "F.Paste" user "Package Geometry/Pastemask Top")
		(15 "B.Paste" user "Package Geometry/Pastemask Bottom")
		(5 "F.SilkS" user "Ref Des/Silkscreen Top")
		(7 "B.SilkS" user "Ref Des/Silkscreen Bottom")
		(1 "F.Mask" user "Board Geometry/Soldermask Top")
		(3 "B.Mask" user "Board Geometry/Soldermask Bottom")
		(17 "Dwgs.User" user "User.Drawings")
		(19 "Cmts.User" user "User.Comments")
		(21 "Eco1.User" user "User.Eco1")
		(23 "Eco2.User" user "User.Eco2")
		(25 "Edge.Cuts" user "Board Geometry/Outline")
		(27 "Margin" user)
		(31 "F.CrtYd" user "Package Geometry/Place Bound Top")
		(29 "B.CrtYd" user "Package Geometry/Place Bound Bottom")
		(35 "F.Fab" user "Ref Des/Assembly Top")
		(33 "B.Fab" user "Ref Des/Assembly Bottom")
	)
	(footprint ""
		(layer "F.Cu")
		(at 70.739 -52.578)
		(property "Reference" "R1172"
			(at 0 0 0)
			(layer "F.SilkS")
			(hide yes)
			(effects
				(font
					(size 1.27 1.27)
				)
			)
		)
		(property "Value" ""
			(at 0 0 0)
			(layer "F.Fab")
			(effects
				(font
					(size 1.27 1.27)
				)
			)
		)
		(duplicate_pad_numbers_are_jumpers no)
		(fp_line
			(start -0.7874 -0.4064)
			(end 0.7874 -0.4064)
			(stroke
				(width 0.1524)
				(type default)
			)
			(layer "F.SilkS")
		)
		(fp_line
			(start -0.7874 0.4064)
			(end -0.7874 -0.4064)
			(stroke
				(width 0.1524)
				(type default)
			)
			(layer "F.SilkS")
		)
		(fp_line
			(start 0.7874 -0.4064)
			(end 0.7874 0.4064)
			(stroke
				(width 0.1524)
				(type default)
			)
			(layer "F.SilkS")
		)
		(fp_line
			(start 0.7874 0.4064)
			(end -0.7874 0.4064)
			(stroke
				(width 0.1524)
				(type default)
			)
			(layer "F.SilkS")
		)
		(fp_line
			(start -0.67945 -0.305054)
			(end -0.12065 -0.305054)
			(stroke
				(width 0.1)
				(type default)
			)
			(layer "F.Fab")
		)
		(fp_line
			(start -0.67945 0.3048)
			(end -0.67945 -0.305054)
			(stroke
				(width 0.1)
				(type default)
			)
			(layer "F.Fab")
		)
		(fp_line
			(start -0.12065 -0.305054)
			(end -0.12065 -0.2794)
			(stroke
				(width 0.1)
				(type default)
			)
			(layer "F.Fab")
		)
		(fp_line
			(start -0.12065 -0.2794)
			(end 0.12065 -0.2794)
			(stroke
				(width 0.1)
				(type default)
			)
			(layer "F.Fab")
		)
		(fp_line
			(start -0.12065 0.2794)
			(end -0.12065 0.3048)
			(stroke
				(width 0.1)
				(type default)
			)
			(layer "F.Fab")
		)
		(fp_line
			(start -0.12065 0.3048)
			(end -0.67945 0.3048)
			(stroke
				(width 0.1)
				(type default)
			)
			(layer "F.Fab")
		)
		(fp_line
			(start 0.120396 0.2794)
			(end -0.12065 0.2794)
			(stroke
				(width 0.1)
				(type default)
			)
			(layer "F.Fab")
		)
		(fp_line
			(start 0.120396 0.3048)
			(end 0.120396 0.2794)
			(stroke
				(width 0.1)
				(type default)
			)
			(layer "F.Fab")
		)
		(fp_line
			(start 0.12065 -0.3048)
			(end 0.67945 -0.3048)
			(stroke
				(width 0.1)
				(type default)
			)
			(layer "F.Fab")
		)
		(fp_line
			(start 0.12065 -0.2794)
			(end 0.12065 -0.3048)
			(stroke
				(width 0.1)
				(type default)
			)
			(layer "F.Fab")
		)
		(fp_line
			(start 0.67945 -0.3048)
			(end 0.67945 0.3048)
			(stroke
				(width 0.1)
				(type default)
			)
			(layer "F.Fab")
		)
		(fp_line
			(start 0.67945 0.3048)
			(end 0.120396 0.3048)
			(stroke
				(width 0.1)
				(type default)
			)
			(layer "F.Fab")
		)
		(pad "1" smd circle
			(at -0.40005 0)
			(size 0 0)
			(layers "F.Cu" "F.Mask" "F.Paste")
			(net "P3V3_AUX")
		)
		(pad "2" smd circle
			(at 0.40005 0)
			(size 0 0)
			(layers "F.Cu" "F.Mask" "F.Paste")
			(net "OCP_V3_2_AUX_PWR_EN")
		)
	)
	(footprint ""
		(layer "F.Cu")
		(at 322.364862 -403.21484 90)
		(property "Reference" "R6808"
			(at 0 0 90)
			(layer "F.SilkS")
			(hide yes)
			(effects
				(font
					(size 1.27 1.27)
				)
			)
		)
		(property "Value" ""
			(at 0 0 90)
			(layer "F.Fab")
			(effects
				(font
					(size 1.27 1.27)
				)
			)
		)
		(duplicate_pad_numbers_are_jumpers no)
		(fp_line
			(start 0.32512 -0.175006)
			(end 0.32512 0.175006)
			(stroke
				(width 0.1)
				(type default)
			)
			(layer "F.Fab")
		)
		(fp_line
			(start -0.32512 -0.175006)
			(end 0.32512 -0.175006)
			(stroke
				(width 0.1)
				(type default)
			)
			(layer "F.Fab")
		)
		(fp_line
			(start 0.32512 0.175006)
			(end -0.32512 0.175006)
			(stroke
				(width 0.1)
				(type default)
			)
			(layer "F.Fab")
		)
		(fp_line
			(start -0.32512 0.175006)
			(end -0.32512 -0.175006)
			(stroke
				(width 0.1)
				(type default)
			)
			(layer "F.Fab")
		)
		(pad "1" smd rect
			(at -0.2667 0 90)
			(size 0.3048 0.381)
			(layers "F.Cu" "F.Mask" "F.Paste")
			(net "P1V8_CPU0_RT_1D")
		)
		(pad "2" smd rect
			(at 0.2667 0 270)
			(size 0.3048 0.381)
			(layers "F.Cu" "F.Mask" "F.Paste")
			(net "RT_CPU0_P0_VQPS")
		)
	)
	(footprint ""
		(layer "F.Cu")
		(at 111.91494 -394.166852 -90)
		(property "Reference" "R908"
			(at 0 0 270)
			(layer "F.SilkS")
			(hide yes)
			(effects
				(font
					(size 1.27 1.27)
				)
			)
		)
		(property "Value" ""
			(at 0 0 270)
			(layer "F.Fab")
			(effects
				(font
					(size 1.27 1.27)
				)
			)
		)
		(duplicate_pad_numbers_are_jumpers no)
		(fp_line
			(start -0.32512 0.175006)
			(end -0.32512 -0.175006)
			(stroke
				(width 0.1)
				(type default)
			)
			(layer "F.Fab")
		)
		(fp_line
			(start 0.32512 0.175006)
			(end -0.32512 0.175006)
			(stroke
				(width 0.1)
				(type default)
			)
			(layer "F.Fab")
		)
		(fp_line
			(start -0.32512 -0.175006)
			(end 0.32512 -0.175006)
			(stroke
				(width 0.1)
				(type default)
			)
			(layer "F.Fab")
		)
		(fp_line
			(start 0.32512 -0.175006)
			(end 0.32512 0.175006)
			(stroke
				(width 0.1)
				(type default)
			)
			(layer "F.Fab")
		)
		(pad "1" smd rect
			(at -0.2667 0 270)
			(size 0.3048 0.381)
			(layers "F.Cu" "F.Mask" "F.Paste")
			(net "RST_RT_CPU1_P3_RESET_R_N")
		)
		(pad "2" smd rect
			(at 0.2667 0 90)
			(size 0.3048 0.381)
			(layers "F.Cu" "F.Mask" "F.Paste")
			(net "GND")
		)
	)
)
